(kicad_pcb
	(version 20241229)
	(generator "pcbnew")
	(generator_version "9.0")
	(general
		(thickness 1.711)
		(legacy_teardrops no)
	)
	(paper "A4")
	(title_block
		(title "Antmicro Baseboard for Jetson AGX Thor")
		(date "2026-02-18")
		(rev "1.1.0")
		(company "Antmicro Ltd")
		(comment 1 "www.antmicro.com")
		(comment 9 "footprints 334-336 of 1170")
	)
	(layers
		(0 "F.Cu" signal)
		(4 "In1.Cu" signal)
		(6 "In2.Cu" signal)
		(8 "In3.Cu" signal)
		(10 "In4.Cu" jumper)
		(12 "In5.Cu" signal)
		(14 "In6.Cu" signal)
		(16 "In7.Cu" signal)
		(18 "In8.Cu" signal)
		(2 "B.Cu" signal)
		(9 "F.Adhes" user "F.Adhesive")
		(11 "B.Adhes" user "B.Adhesive")
		(13 "F.Paste" user)
		(15 "B.Paste" user)
		(5 "F.SilkS" user "F.Silkscreen")
		(7 "B.SilkS" user "B.Silkscreen")
		(1 "F.Mask" user)
		(3 "B.Mask" user)
		(17 "Dwgs.User" user "User.Drawings")
		(19 "Cmts.User" user "User.Comments")
		(21 "Eco1.User" user "User.Eco1")
		(23 "Eco2.User" user "User.Eco2")
		(25 "Edge.Cuts" user)
		(27 "Margin" user)
		(31 "F.CrtYd" user "F.Courtyard")
		(29 "B.CrtYd" user "B.Courtyard")
		(35 "F.Fab" user)
		(33 "B.Fab" user)
	)
	(footprint "antmicro-footprints:XSON-8_1x1.95mm_P0.5mm"
		(layer "F.Cu")
		(at 157.31 143.43 90)
		(property "Reference" "U51"
			(at 3.43 -1.41 180)
			(layer "F.SilkS")
			(effects
				(font
					(size 0.7 0.7)
					(thickness 0.15)
				)
				(justify left bottom)
			)
		)
		(property "Value" "NTS0102_XSON"
			(at 0 2.2 90)
			(layer "F.Fab")
			(effects
				(font
					(size 0.7 0.7)
					(thickness 0.15)
				)
				(justify left bottom)
			)
		)
		(property "Datasheet" "http://www.farnell.com/datasheets/1760723.pdf"
			(at 0 0 90)
			(layer "F.Fab")
			(hide yes)
			(effects
				(font
					(size 1.27 1.27)
					(thickness 0.15)
				)
			)
		)
		(property "Description" "Transceiver, 1.65 V to 3.6 V, XSON-8"
			(at 0 0 90)
			(layer "F.Fab")
			(hide yes)
			(effects
				(font
					(size 1.27 1.27)
					(thickness 0.15)
				)
			)
		)
		(property "MPN" "NTS0102GT"
			(at 0 0 90)
			(unlocked yes)
			(layer "F.Fab")
			(hide yes)
			(effects
				(font
					(size 1 1)
					(thickness 0.15)
				)
			)
		)
		(property "Manufacturer" "NXP"
			(at 0 0 90)
			(unlocked yes)
			(layer "F.Fab")
			(hide yes)
			(effects
				(font
					(size 1 1)
					(thickness 0.15)
				)
			)
		)
		(property "Author" "Antmicro"
			(at 0 0 90)
			(unlocked yes)
			(layer "F.Fab")
			(hide yes)
			(effects
				(font
					(size 1 1)
					(thickness 0.15)
				)
			)
		)
		(property "License" "Apache-2.0"
			(at 0 0 90)
			(unlocked yes)
			(layer "F.Fab")
			(hide yes)
			(effects
				(font
					(size 1 1)
					(thickness 0.15)
				)
			)
		)
		(sheetname "/Peripherals/")
		(sheetfile "peripherals.kicad_sch")
		(attr smd)
		(fp_line
			(start -0.5 -1.1)
			(end 0.5 -1.1)
			(stroke
				(width 0.15)
				(type solid)
			)
			(layer "F.SilkS")
		)
		(fp_line
			(start 0.5 1.1)
			(end -0.5 1.1)
			(stroke
				(width 0.15)
				(type solid)
			)
			(layer "F.SilkS")
		)
		(fp_circle
			(center -0.75 -1.1)
			(end -0.701 -1.1)
			(stroke
				(width 0.15)
				(type solid)
			)
			(fill no)
			(layer "F.SilkS")
		)
		(fp_rect
			(start -0.8 -1.2)
			(end 0.8 1.2)
			(stroke
				(width 0.05)
				(type solid)
			)
			(fill no)
			(layer "F.CrtYd")
		)
		(fp_line
			(start 0.5305 -1.001)
			(end 0.5305 1)
			(stroke
				(width 0.15)
				(type solid)
			)
			(layer "F.Fab")
		)
		(fp_line
			(start -0.5305 -1.001)
			(end 0.5305 -1.001)
			(stroke
				(width 0.15)
				(type solid)
			)
			(layer "F.Fab")
		)
		(fp_line
			(start 0.5305 1)
			(end -0.5305 1)
			(stroke
				(width 0.15)
				(type solid)
			)
			(layer "F.Fab")
		)
		(fp_line
			(start -0.5305 1)
			(end -0.5305 -1.001)
			(stroke
				(width 0.15)
				(type solid)
			)
			(layer "F.Fab")
		)
		(fp_text user "License: Apache-2.0"
			(at -0.527 8.306 90)
			(layer "F.Fab")
			(effects
				(font
					(size 0.7 0.7)
					(thickness 0.15)
				)
				(justify left bottom)
			)
		)
		(fp_text user "${REFERENCE}"
			(at -0.527 5.905 90)
			(layer "F.Fab")
			(effects
				(font
					(size 0.7 0.7)
					(thickness 0.15)
				)
				(justify left bottom)
			)
		)
		(fp_text user "Author: Antmicro"
			(at -0.527 7.105 90)
			(layer "F.Fab")
			(effects
				(font
					(size 0.7 0.7)
					(thickness 0.15)
				)
				(justify left bottom)
			)
		)
		(pad "1" smd roundrect
			(at -0.45 -0.75 270)
			(size 0.6 0.3)
			(layers "F.Cu" "F.Mask" "F.Paste")
			(roundrect_rratio 0.25)
			(net 279 "/Peripherals/FAN_TACH_5V")
			(pinfunction "B_{2}")
			(pintype "bidirectional")
		)
		(pad "2" smd roundrect
			(at -0.45 -0.25 270)
			(size 0.6 0.25)
			(layers "F.Cu" "F.Mask" "F.Paste")
			(roundrect_rratio 0.25)
			(net 1 "GND")
			(pinfunction "GND")
			(pintype "power_in")
		)
		(pad "3" smd roundrect
			(at -0.45 0.25 270)
			(size 0.6 0.25)
			(layers "F.Cu" "F.Mask" "F.Paste")
			(roundrect_rratio 0.25)
			(net 11 "+1V8")
			(pinfunction "VCC_{A}")
			(pintype "power_in")
		)
		(pad "4" smd roundrect
			(at -0.45 0.75 270)
			(size 0.6 0.3)
			(layers "F.Cu" "F.Mask" "F.Paste")
			(roundrect_rratio 0.25)
			(net 100 "/Peripherals/FAN_TACH")
			(pinfunction "A_{2}")
			(pintype "bidirectional")
		)
		(pad "5" smd roundrect
			(at 0.45 0.75 270)
			(size 0.6 0.3)
			(layers "F.Cu" "F.Mask" "F.Paste")
			(roundrect_rratio 0.25)
			(net 97 "/Peripherals/FAN_PWM")
			(pinfunction "A_{1}")
			(pintype "bidirectional")
		)
		(pad "6" smd roundrect
			(at 0.45 0.25 270)
			(size 0.6 0.25)
			(layers "F.Cu" "F.Mask" "F.Paste")
			(roundrect_rratio 0.25)
			(net 11 "+1V8")
			(pinfunction "OE")
			(pintype "input")
		)
		(pad "7" smd roundrect
			(at 0.45 -0.25 270)
			(size 0.6 0.25)
			(layers "F.Cu" "F.Mask" "F.Paste")
			(roundrect_rratio 0.25)
			(net 5 "+5V")
			(pinfunction "VCC_{B}")
			(pintype "power_in")
		)
		(pad "8" smd roundrect
			(at 0.45 -0.75 270)
			(size 0.6 0.3)
			(layers "F.Cu" "F.Mask" "F.Paste")
			(roundrect_rratio 0.25)
			(net 281 "/Peripherals/FAN_PWM_5V")
			(pinfunction "B_{1}")
			(pintype "bidirectional")
		)
	)
	(footprint "antmicro-footprints:R_0402_1005Metric"
		(layer "F.Cu")
		(at 195.1 125.3)
		(descr "Resistor SMD 0402")
		(tags "resistor SMD 0402")
		(property "Reference" "R86"
			(at 0.15 -1.225 0)
			(layer "F.SilkS")
			(effects
				(font
					(size 0.7 0.7)
					(thickness 0.15)
				)
				(justify left bottom)
			)
		)
		(property "Value" "R_10k_0402"
			(at -1.011843 1.772047 0)
			(layer "F.Fab")
			(effects
				(font
					(size 0.7 0.7)
					(thickness 0.15)
				)
				(justify left bottom)
			)
		)
		(property "Datasheet" "https://www.bourns.com/docs/product-datasheets/cr.pdf"
			(at 0 0 0)
			(layer "F.Fab")
			(hide yes)
			(effects
				(font
					(size 1.27 1.27)
					(thickness 0.15)
				)
			)
		)
		(property "Description" "SMD Chip Resistor, 10 kohm, ± 1%, 62.5 mW, 0402 [1005 Metric], Thick Film, General Purpose"
			(at 0 0 0)
			(layer "F.Fab")
			(hide yes)
			(effects
				(font
					(size 1.27 1.27)
					(thickness 0.15)
				)
			)
		)
		(property "MPN" "CR0402-FX-1002GLF"
			(at 0 0 0)
			(unlocked yes)
			(layer "F.Fab")
			(hide yes)
			(effects
				(font
					(size 1 1)
					(thickness 0.15)
				)
			)
		)
		(property "Manufacturer" "Bourns"
			(at 0 0 0)
			(unlocked yes)
			(layer "F.Fab")
			(hide yes)
			(effects
				(font
					(size 1 1)
					(thickness 0.15)
				)
			)
		)
		(property "License" "Apache-2.0"
			(at 0 0 0)
			(unlocked yes)
			(layer "F.Fab")
			(hide yes)
			(effects
				(font
					(size 1 1)
					(thickness 0.15)
				)
			)
		)
		(property "Author" "Antmicro"
			(at 0 0 0)
			(unlocked yes)
			(layer "F.Fab")
			(hide yes)
			(effects
				(font
					(size 1 1)
					(thickness 0.15)
				)
			)
		)
		(property "Val" "10k"
			(at 0 0 0)
			(unlocked yes)
			(layer "F.Fab")
			(hide yes)
			(effects
				(font
					(size 1 1)
					(thickness 0.15)
				)
			)
		)
		(property "Tolerance" "1%"
			(at 0 0 0)
			(unlocked yes)
			(layer "F.Fab")
			(hide yes)
			(effects
				(font
					(size 1 1)
					(thickness 0.15)
				)
			)
		)
		(sheetname "/USB Hub/")
		(sheetfile "usb_hub.kicad_sch")
		(attr smd)
		(fp_rect
			(start -0.925 -0.47)
			(end 0.925 0.47)
			(stroke
				(width 0.05)
				(type default)
			)
			(fill no)
			(layer "F.CrtYd")
		)
		(fp_rect
			(start -0.5 -0.25)
			(end 0.5 0.25)
			(stroke
				(width 0.15)
				(type solid)
			)
			(fill no)
			(layer "F.Fab")
		)
		(fp_text user "Author: Antmicro"
			(at -0.95 4.169 0)
			(layer "F.Fab")
			(effects
				(font
					(size 0.7 0.7)
					(thickness 0.15)
				)
				(justify left bottom)
			)
		)
		(fp_text user "License: Apache-2.0"
			(at -0.95 5.169 0)
			(layer "F.Fab")
			(effects
				(font
					(size 0.7 0.7)
					(thickness 0.15)
				)
				(justify left bottom)
			)
		)
		(fp_text user "${REFERENCE}"
			(at -0.95 3.168 0)
			(layer "F.Fab")
			(effects
				(font
					(size 0.7 0.7)
					(thickness 0.15)
				)
				(justify left bottom)
			)
		)
		(pad "1" smd roundrect
			(at -0.48 0)
			(size 0.59 0.64)
			(layers "F.Cu" "F.Mask" "F.Paste")
			(roundrect_rratio 0.25)
			(net 2 "+3V3")
			(pintype "passive")
		)
		(pad "2" smd roundrect
			(at 0.48 0)
			(size 0.59 0.64)
			(layers "F.Cu" "F.Mask" "F.Paste")
			(roundrect_rratio 0.25)
			(net 920 "/USB Hub/TEST1")
			(pintype "passive")
		)
	)
	(footprint "antmicro-footprints:C_0402_1005Metric"
		(layer "F.Cu")
		(at 182.84 69.59 -90)
		(descr "Capacitor SMD 0402")
		(tags "capacitor SMD 0402")
		(property "Reference" "C279"
			(at -1.12 -1.779468 90)
			(layer "F.SilkS")
			(effects
				(font
					(size 0.7 0.7)
					(thickness 0.15)
				)
				(justify right top)
			)
		)
		(property "Value" "C_1u_0402"
			(at -1.022927 2.155213 90)
			(layer "F.Fab")
			(effects
				(font
					(size 0.7 0.7)
					(thickness 0.15)
				)
				(justify right top)
			)
		)
		(property "Datasheet" "https://product.tdk.com/en/search/capacitor/ceramic/mlcc/info?part_no=C1005X6S1A105K050BC"
			(at 0 0 90)
			(layer "F.Fab")
			(hide yes)
			(effects
				(font
					(size 1.27 1.27)
					(thickness 0.15)
				)
			)
		)
		(property "Description" "SMD Multilayer Ceramic Capacitor, 1 µF, 10 V, 0402 [1005 Metric], ± 10%, X6S, C"
			(at 0 0 90)
			(layer "F.Fab")
			(hide yes)
			(effects
				(font
					(size 1.27 1.27)
					(thickness 0.15)
				)
			)
		)
		(property "Manufacturer" "TDK"
			(at 0 0 270)
			(unlocked yes)
			(layer "F.Fab")
			(hide yes)
			(effects
				(font
					(size 1 1)
					(thickness 0.15)
				)
			)
		)
		(property "MPN" "C1005X6S1A105K050BC"
			(at 0 0 270)
			(unlocked yes)
			(layer "F.Fab")
			(hide yes)
			(effects
				(font
					(size 1 1)
					(thickness 0.15)
				)
			)
		)
		(property "Val" "1u"
			(at 0 0 270)
			(unlocked yes)
			(layer "F.Fab")
			(hide yes)
			(effects
				(font
					(size 1 1)
					(thickness 0.15)
				)
			)
		)
		(property "License" "Apache-2.0"
			(at 0 0 270)
			(unlocked yes)
			(layer "F.Fab")
			(hide yes)
			(effects
				(font
					(size 1 1)
					(thickness 0.15)
				)
			)
		)
		(property "Author" "Antmicro"
			(at 0 0 270)
			(unlocked yes)
			(layer "F.Fab")
			(hide yes)
			(effects
				(font
					(size 1 1)
					(thickness 0.15)
				)
			)
		)
		(property "Voltage" ""
			(at 0 0 270)
			(unlocked yes)
			(layer "F.Fab")
			(hide yes)
			(effects
				(font
					(size 1 1)
					(thickness 0.15)
				)
			)
		)
		(property "Dielectric" ""
			(at 0 0 270)
			(unlocked yes)
			(layer "F.Fab")
			(hide yes)
			(effects
				(font
					(size 1 1)
					(thickness 0.15)
				)
			)
		)
		(component_classes
			(class "DCDC_20V")
		)
		(sheetname "/DCDC/")
		(sheetfile "dcdc.kicad_sch")
		(attr smd)
		(fp_rect
			(start -0.925 -0.47)
			(end 0.925 0.47)
			(stroke
				(width 0.05)
				(type default)
			)
			(fill no)
			(layer "F.CrtYd")
		)
		(fp_line
			(start -0.494 0.248)
			(end -0.494 -0.25)
			(stroke
				(width 0.15)
				(type solid)
			)
			(layer "F.Fab")
		)
		(fp_line
			(start 0.504 0.248)
			(end -0.494 0.248)
			(stroke
				(width 0.15)
				(type solid)
			)
			(layer "F.Fab")
		)
		(fp_line
			(start -0.494 -0.25)
			(end 0.504 -0.25)
			(stroke
				(width 0.15)
				(type solid)
			)
			(layer "F.Fab")
		)
		(fp_line
			(start 0.504 -0.25)
			(end 0.504 0.248)
			(stroke
				(width 0.15)
				(type solid)
			)
			(layer "F.Fab")
		)
		(fp_text user "License: Apache-2.0"
			(at -0.939 5.799 90)
			(layer "F.Fab")
			(effects
				(font
					(size 0.7 0.7)
					(thickness 0.15)
				)
				(justify right top)
			)
		)
		(fp_text user "${REFERENCE}"
			(at -0.939 4.599 90)
			(layer "F.Fab")
			(effects
				(font
					(size 0.7 0.7)
					(thickness 0.15)
				)
				(justify right top)
			)
		)
		(fp_text user "Author: Antmicro"
			(at -0.939 3.399 90)
			(layer "F.Fab")
			(effects
				(font
					(size 0.7 0.7)
					(thickness 0.15)
				)
				(justify right top)
			)
		)
		(pad "1" smd roundrect
			(at -0.48 0 270)
			(size 0.59 0.64)
			(layers "F.Cu" "F.Mask" "F.Paste")
			(roundrect_rratio 0.25)
			(net 1 "GND")
			(pintype "passive")
		)
		(pad "2" smd roundrect
			(at 0.48 0 270)
			(size 0.59 0.64)
			(layers "F.Cu" "F.Mask" "F.Paste")
			(roundrect_rratio 0.25)
			(net 905 "/DCDC/20V_VDD")
			(pintype "passive")
		)
	)
)
